# S9S_MB_2U (Grand Teton) — schematic netlist excerpt (pin names and nets, part order shuffled) for the footprints in the layout excerpt that follows; sources: Cadence DE-HDL packaged netlist, KiCad conversion of 03242023_DA0F0TMBIJ0_F0T_Motherboard_J_brd_V01_OCP.brd

PR4217  Q_RES  0 5% EMPTY  pkg 0402LF  page 266 : A = PVCCFA_EHV_FIVRA_CPU0_IMON4 ; B = GND
R946  Q_RES  10K 1% CHIP  pkg 0402LF  page 115 : A = P3V3_AUX ; B = PWRGD_FAIL_CPU1_EF_R1
PC513_P1_6  Q_CAP  22UF 16V 20% X6S  pkg C0805  page 287 : A = SW_P12V_PVCCIN_CPU1_FLT ; B = GND

(kicad_pcb
	(version 20260206)
	(generator "pcbnew")
	(generator_version "10.0")
	(general
		(thickness 1.6)
		(legacy_teardrops no)
	)
	(paper "A4")
	(title_block
		(title "03242023_DA0F0TMBIJ0_F0T_Motherboard_J_brd_V01_OCP.brd")
		(comment 1 "Grand Teton / footprints 5058-5060 of 6105")
	)
	(layers
		(0 "F.Cu" signal "TOP")
		(4 "In1.Cu" signal "GND")
		(6 "In2.Cu" signal "IN1")
		(8 "In3.Cu" signal "GND1")
		(10 "In4.Cu" signal "IN2")
		(12 "In5.Cu" signal "GND2")
		(14 "In6.Cu" signal "IN3")
		(16 "In7.Cu" signal "GND3")
		(18 "In8.Cu" signal "VCC")
		(20 "In9.Cu" signal "VCC1")
		(22 "In10.Cu" signal "GND4")
		(24 "In11.Cu" signal "IN4")
		(26 "In12.Cu" signal "GND5")
		(28 "In13.Cu" signal "IN5")
		(30 "In14.Cu" signal "GND6")
		(32 "In15.Cu" signal "IN6")
		(34 "In16.Cu" signal "GND7")
		(2 "B.Cu" signal "BOTTOM")
		(9 "F.Adhes" user "F.Adhesive")
		(11 "B.Adhes" user "B.Adhesive")
		(13 "F.Paste" user "Package Geometry/Pastemask Top")
		(15 "B.Paste" user "Package Geometry/Pastemask Bottom")
		(5 "F.SilkS" user "Ref Des/Silkscreen Top")
		(7 "B.SilkS" user "Ref Des/Silkscreen Bottom")
		(1 "F.Mask" user "Board Geometry/Soldermask Top")
		(3 "B.Mask" user "Board Geometry/Soldermask Bottom")
		(17 "Dwgs.User" user "User.Drawings")
		(19 "Cmts.User" user "User.Comments")
		(21 "Eco1.User" user "User.Eco1")
		(23 "Eco2.User" user "User.Eco2")
		(25 "Edge.Cuts" user "Board Geometry/Outline")
		(27 "Margin" user)
		(31 "F.CrtYd" user "Package Geometry/Place Bound Top")
		(29 "B.CrtYd" user "Package Geometry/Place Bound Bottom")
		(35 "F.Fab" user "Ref Des/Assembly Top")
		(33 "B.Fab" user "Ref Des/Assembly Bottom")
	)
	(footprint ""
		(layer "B.Cu")
		(at 186.464194 -319.028826 90)
		(property "Reference" "R946"
			(at 0 0 90)
			(layer "B.SilkS")
			(hide yes)
			(effects
				(font
					(size 1.27 1.27)
				)
				(justify mirror)
			)
		)
		(property "Value" ""
			(at 0 0 90)
			(layer "B.Fab")
			(effects
				(font
					(size 1.27 1.27)
				)
				(justify mirror)
			)
		)
		(duplicate_pad_numbers_are_jumpers no)
		(fp_line
			(start 0.7874 -0.4064)
			(end -0.7874 -0.4064)
			(stroke
				(width 0.1524)
				(type default)
			)
			(layer "B.SilkS")
		)
		(fp_line
			(start -0.7874 -0.4064)
			(end -0.7874 0.4064)
			(stroke
				(width 0.1524)
				(type default)
			)
			(layer "B.SilkS")
		)
		(fp_line
			(start 0.7874 0.4064)
			(end 0.7874 -0.4064)
			(stroke
				(width 0.1524)
				(type default)
			)
			(layer "B.SilkS")
		)
		(fp_line
			(start -0.7874 0.4064)
			(end 0.7874 0.4064)
			(stroke
				(width 0.1524)
				(type default)
			)
			(layer "B.SilkS")
		)
		(fp_line
			(start 0.67945 -0.305054)
			(end 0.12065 -0.305054)
			(stroke
				(width 0.1)
				(type default)
			)
			(layer "B.Fab")
		)
		(fp_line
			(start 0.12065 -0.305054)
			(end 0.12065 -0.2794)
			(stroke
				(width 0.1)
				(type default)
			)
			(layer "B.Fab")
		)
		(fp_line
			(start -0.12065 -0.3048)
			(end -0.67945 -0.3048)
			(stroke
				(width 0.1)
				(type default)
			)
			(layer "B.Fab")
		)
		(fp_line
			(start -0.67945 -0.3048)
			(end -0.67945 0.3048)
			(stroke
				(width 0.1)
				(type default)
			)
			(layer "B.Fab")
		)
		(fp_line
			(start 0.12065 -0.2794)
			(end -0.12065 -0.2794)
			(stroke
				(width 0.1)
				(type default)
			)
			(layer "B.Fab")
		)
		(fp_line
			(start -0.12065 -0.2794)
			(end -0.12065 -0.3048)
			(stroke
				(width 0.1)
				(type default)
			)
			(layer "B.Fab")
		)
		(fp_line
			(start 0.12065 0.2794)
			(end 0.12065 0.3048)
			(stroke
				(width 0.1)
				(type default)
			)
			(layer "B.Fab")
		)
		(fp_line
			(start -0.120396 0.2794)
			(end 0.12065 0.2794)
			(stroke
				(width 0.1)
				(type default)
			)
			(layer "B.Fab")
		)
		(fp_line
			(start 0.67945 0.3048)
			(end 0.67945 -0.305054)
			(stroke
				(width 0.1)
				(type default)
			)
			(layer "B.Fab")
		)
		(fp_line
			(start 0.12065 0.3048)
			(end 0.67945 0.3048)
			(stroke
				(width 0.1)
				(type default)
			)
			(layer "B.Fab")
		)
		(fp_line
			(start -0.120396 0.3048)
			(end -0.120396 0.2794)
			(stroke
				(width 0.1)
				(type default)
			)
			(layer "B.Fab")
		)
		(fp_line
			(start -0.67945 0.3048)
			(end -0.120396 0.3048)
			(stroke
				(width 0.1)
				(type default)
			)
			(layer "B.Fab")
		)
		(pad "1" smd circle
			(at 0.40005 0 270)
			(size 0 0)
			(layers "B.Cu" "B.Mask" "B.Paste")
			(net "P3V3_AUX")
		)
		(pad "2" smd circle
			(at -0.40005 0 270)
			(size 0 0)
			(layers "B.Cu" "B.Mask" "B.Paste")
			(net "PWRGD_FAIL_CPU1_EF_R1")
		)
	)
	(footprint ""
		(layer "B.Cu")
		(at 90.340688 -341.017606 -90)
		(property "Reference" "PC513_P1_6"
			(at 0 0 90)
			(layer "B.SilkS")
			(hide yes)
			(effects
				(font
					(size 1.27 1.27)
				)
				(justify mirror)
			)
		)
		(property "Value" ""
			(at 0 0 90)
			(layer "B.Fab")
			(effects
				(font
					(size 1.27 1.27)
				)
				(justify mirror)
			)
		)
		(duplicate_pad_numbers_are_jumpers no)
		(fp_line
			(start -1.524 0.762)
			(end 1.524 0.762)
			(stroke
				(width 0.1524)
				(type default)
			)
			(layer "B.SilkS")
		)
		(fp_line
			(start 1.524 0.762)
			(end 1.524 -0.762)
			(stroke
				(width 0.1524)
				(type default)
			)
			(layer "B.SilkS")
		)
		(fp_line
			(start -1.524 -0.762)
			(end -1.524 0.762)
			(stroke
				(width 0.1524)
				(type default)
			)
			(layer "B.SilkS")
		)
		(fp_line
			(start 1.524 -0.762)
			(end -1.524 -0.762)
			(stroke
				(width 0.1524)
				(type default)
			)
			(layer "B.SilkS")
		)
		(fp_line
			(start -1.1049 0.724916)
			(end -1.1049 -0.724916)
			(stroke
				(width 0.1)
				(type default)
			)
			(layer "B.Fab")
		)
		(fp_line
			(start 1.1049 0.724916)
			(end -1.1049 0.724916)
			(stroke
				(width 0.1)
				(type default)
			)
			(layer "B.Fab")
		)
		(fp_line
			(start -1.1049 -0.724916)
			(end 1.1049 -0.724916)
			(stroke
				(width 0.1)
				(type default)
			)
			(layer "B.Fab")
		)
		(fp_line
			(start 1.1049 -0.724916)
			(end 1.1049 0.724916)
			(stroke
				(width 0.1)
				(type default)
			)
			(layer "B.Fab")
		)
		(pad "1" smd rect
			(at 0.889 0 270)
			(size 1.016 1.27)
			(layers "B.Cu" "B.Mask" "B.Paste")
			(net "SW_P12V_PVCCIN_CPU1_FLT")
		)
		(pad "2" smd rect
			(at -0.889 0 270)
			(size 1.016 1.27)
			(layers "B.Cu" "B.Mask" "B.Paste")
			(net "GND")
		)
	)
	(footprint ""
		(layer "B.Cu")
		(at 286.0294 -367.355628 -90)
		(property "Reference" "PR4217"
			(at 0 0 90)
			(layer "B.SilkS")
			(hide yes)
			(effects
				(font
					(size 1.27 1.27)
				)
				(justify mirror)
			)
		)
		(property "Value" ""
			(at 0 0 90)
			(layer "B.Fab")
			(effects
				(font
					(size 1.27 1.27)
				)
				(justify mirror)
			)
		)
		(duplicate_pad_numbers_are_jumpers no)
		(fp_line
			(start -0.7874 0.4064)
			(end 0.7874 0.4064)
			(stroke
				(width 0.1524)
				(type default)
			)
			(layer "B.SilkS")
		)
		(fp_line
			(start 0.7874 0.4064)
			(end 0.7874 -0.4064)
			(stroke
				(width 0.1524)
				(type default)
			)
			(layer "B.SilkS")
		)
		(fp_line
			(start -0.7874 -0.4064)
			(end -0.7874 0.4064)
			(stroke
				(width 0.1524)
				(type default)
			)
			(layer "B.SilkS")
		)
		(fp_line
			(start 0.7874 -0.4064)
			(end -0.7874 -0.4064)
			(stroke
				(width 0.1524)
				(type default)
			)
			(layer "B.SilkS")
		)
		(fp_line
			(start -0.67945 0.3048)
			(end -0.120396 0.3048)
			(stroke
				(width 0.1)
				(type default)
			)
			(layer "B.Fab")
		)
		(fp_line
			(start -0.120396 0.3048)
			(end -0.120396 0.2794)
			(stroke
				(width 0.1)
				(type default)
			)
			(layer "B.Fab")
		)
		(fp_line
			(start 0.12065 0.3048)
			(end 0.67945 0.3048)
			(stroke
				(width 0.1)
				(type default)
			)
			(layer "B.Fab")
		)
		(fp_line
			(start 0.67945 0.3048)
			(end 0.67945 -0.305054)
			(stroke
				(width 0.1)
				(type default)
			)
			(layer "B.Fab")
		)
		(fp_line
			(start -0.120396 0.2794)
			(end 0.12065 0.2794)
			(stroke
				(width 0.1)
				(type default)
			)
			(layer "B.Fab")
		)
		(fp_line
			(start 0.12065 0.2794)
			(end 0.12065 0.3048)
			(stroke
				(width 0.1)
				(type default)
			)
			(layer "B.Fab")
		)
		(fp_line
			(start -0.12065 -0.2794)
			(end -0.12065 -0.3048)
			(stroke
				(width 0.1)
				(type default)
			)
			(layer "B.Fab")
		)
		(fp_line
			(start 0.12065 -0.2794)
			(end -0.12065 -0.2794)
			(stroke
				(width 0.1)
				(type default)
			)
			(layer "B.Fab")
		)
		(fp_line
			(start -0.67945 -0.3048)
			(end -0.67945 0.3048)
			(stroke
				(width 0.1)
				(type default)
			)
			(layer "B.Fab")
		)
		(fp_line
			(start -0.12065 -0.3048)
			(end -0.67945 -0.3048)
			(stroke
				(width 0.1)
				(type default)
			)
			(layer "B.Fab")
		)
		(fp_line
			(start 0.12065 -0.305054)
			(end 0.12065 -0.2794)
			(stroke
				(width 0.1)
				(type default)
			)
			(layer "B.Fab")
		)
		(fp_line
			(start 0.67945 -0.305054)
			(end 0.12065 -0.305054)
			(stroke
				(width 0.1)
				(type default)
			)
			(layer "B.Fab")
		)
		(pad "1" smd circle
			(at 0.40005 0 90)
			(size 0 0)
			(layers "B.Cu" "B.Mask" "B.Paste")
			(net "PVCCFA_EHV_FIVRA_CPU0_IMON4")
		)
		(pad "2" smd circle
			(at -0.40005 0 90)
			(size 0 0)
			(layers "B.Cu" "B.Mask" "B.Paste")
			(net "GND")
		)
	)
)
